(kicad_pcb
	(version 20260206)
	(generator "pcbnew")
	(generator_version "10.0")
	(general
		(thickness 1.6)
		(legacy_teardrops no)
	)
	(paper "A4")
	(title_block
		(title "pdpb — Lightning_PDPB_BRD.brd")
		(comment 1 "Lightning (Wiwynn / Facebook NVMe JBOF) / footprints 339-344 of 1140")
	)
	(layers
		(0 "F.Cu" signal "TOP")
		(4 "In1.Cu" signal "L2GND")
		(6 "In2.Cu" signal "L3")
		(8 "In3.Cu" signal "L4VCC")
		(10 "In4.Cu" signal "L5VCC")
		(12 "In5.Cu" signal "L6")
		(14 "In6.Cu" signal "L7GND")
		(2 "B.Cu" signal "BOTTOM")
		(9 "F.Adhes" user "F.Adhesive")
		(11 "B.Adhes" user "B.Adhesive")
		(13 "F.Paste" user "Package Geometry/Pastemask Top")
		(15 "B.Paste" user "Package Geometry/Pastemask Bottom")
		(5 "F.SilkS" user "Ref Des/Silkscreen Top")
		(7 "B.SilkS" user "Ref Des/Silkscreen Bottom")
		(1 "F.Mask" user "Board Geometry/Soldermask Top")
		(3 "B.Mask" user "Board Geometry/Soldermask Bottom")
		(17 "Dwgs.User" user "User.Drawings")
		(19 "Cmts.User" user "User.Comments")
		(21 "Eco1.User" user "User.Eco1")
		(23 "Eco2.User" user "User.Eco2")
		(25 "Edge.Cuts" user "Board Geometry/Outline")
		(27 "Margin" user)
		(31 "F.CrtYd" user "Package Geometry/Place Bound Top")
		(29 "B.CrtYd" user "Package Geometry/Place Bound Bottom")
		(35 "F.Fab" user "Ref Des/Assembly Top")
		(33 "B.Fab" user "Ref Des/Assembly Bottom")
	)
	(footprint ""
		(layer "F.Cu")
		(at 32.004 -318.4652 180)
		(property "Reference" "SR1113"
			(at 0 0 180)
			(layer "F.SilkS")
			(hide yes)
			(effects
				(font
					(size 1.27 1.27)
				)
			)
		)
		(property "Value" "4K7R2F-GP"
			(at 0.064008 -3.993896 180)
			(unlocked yes)
			(layer "F.Fab")
			(hide yes)
			(effects
				(font
					(size 1.016 1.016)
					(thickness 0.1524)
				)
			)
		)
		(property "Device Type" "R402H16"
			(at 0.064008 -5.517896 180)
			(unlocked yes)
			(layer "F.Fab")
			(hide yes)
			(effects
				(font
					(size 1.016 1.016)
					(thickness 0.1524)
				)
			)
		)
		(duplicate_pad_numbers_are_jumpers no)
		(fp_line
			(start 0.508 -0.9398)
			(end -0.508 -0.9398)
			(stroke
				(width 0.1524)
				(type default)
			)
			(layer "F.SilkS")
		)
		(fp_line
			(start -0.508 -0.9398)
			(end -0.508 0.9398)
			(stroke
				(width 0.1524)
				(type default)
			)
			(layer "F.SilkS")
		)
		(fp_rect
			(start -0.508 0.9398)
			(end 0.508 -0.9398)
			(stroke
				(width 0)
				(type default)
			)
			(fill no)
			(layer "F.CrtYd")
		)
		(fp_rect
			(start -0.508 0.9398)
			(end 0.508 -0.9398)
			(stroke
				(width 0)
				(type default)
			)
			(fill no)
			(layer "F.Fab")
		)
		(pad "1" smd custom
			(at 0 -0.4445 180)
			(size 0.1397 0.1397)
			(layers "F.Cu" "F.Mask" "F.Paste")
			(net "P3V3")
			(options
				(clearance outline)
				(anchor circle)
			)
			(primitives
				(gr_poly
					(pts
						(arc
							(start -0.1778 -0.2794)
							(mid -0.249642 -0.249642)
							(end -0.2794 -0.1778)
						)
						(arc
							(start -0.2794 0.1778)
							(mid -0.249642 0.249642)
							(end -0.1778 0.2794)
						)
						(arc
							(start 0.1778 0.2794)
							(mid 0.249642 0.249642)
							(end 0.2794 0.1778)
						)
						(arc
							(start 0.2794 -0.1778)
							(mid 0.249642 -0.249642)
							(end 0.1778 -0.2794)
						)
					)
					(width 0)
					(fill yes)
				)
			)
		)
		(pad "2" smd custom
			(at 0 0.4445 180)
			(size 0.1397 0.1397)
			(layers "F.Cu" "F.Mask" "F.Paste")
			(net "DUALPORTEN#11")
			(options
				(clearance outline)
				(anchor circle)
			)
			(primitives
				(gr_poly
					(pts
						(arc
							(start -0.1778 -0.2794)
							(mid -0.249642 -0.249642)
							(end -0.2794 -0.1778)
						)
						(arc
							(start -0.2794 0.1778)
							(mid -0.249642 0.249642)
							(end -0.1778 0.2794)
						)
						(arc
							(start 0.1778 0.2794)
							(mid 0.249642 0.249642)
							(end 0.2794 0.1778)
						)
						(arc
							(start 0.2794 -0.1778)
							(mid 0.249642 -0.249642)
							(end 0.1778 -0.2794)
						)
					)
					(width 0)
					(fill yes)
				)
			)
		)
	)
	(footprint ""
		(layer "F.Cu")
		(at 233.807 -35.802062 180)
		(property "Reference" "Q48"
			(at 0 0 180)
			(layer "F.SilkS")
			(hide yes)
			(effects
				(font
					(size 1.27 1.27)
				)
			)
		)
		(property "Value" "2N7002A-7-GP"
			(at 0.127 -8.9662 180)
			(unlocked yes)
			(layer "F.Fab")
			(hide yes)
			(effects
				(font
					(size 1.016 1.016)
					(thickness 0.1524)
				)
			)
		)
		(property "Device Type" "SOT23DGS2D4H48"
			(at 0.127 -10.4902 180)
			(unlocked yes)
			(layer "F.Fab")
			(hide yes)
			(effects
				(font
					(size 1.016 1.016)
					(thickness 0.1524)
				)
			)
		)
		(duplicate_pad_numbers_are_jumpers no)
		(fp_line
			(start 1.651 1.778)
			(end 1.651 -1.778)
			(stroke
				(width 0.1524)
				(type default)
			)
			(layer "F.SilkS")
		)
		(fp_line
			(start 1.651 -1.778)
			(end -1.651 -1.778)
			(stroke
				(width 0.1524)
				(type default)
			)
			(layer "F.SilkS")
		)
		(fp_line
			(start -1.651 1.778)
			(end 1.651 1.778)
			(stroke
				(width 0.1524)
				(type default)
			)
			(layer "F.SilkS")
		)
		(fp_line
			(start -1.651 -1.778)
			(end -1.651 1.778)
			(stroke
				(width 0.1524)
				(type default)
			)
			(layer "F.SilkS")
		)
		(fp_poly
			(pts
				(xy -1.778 1.8796) (xy -1.778 -1.8796) (xy 1.778 -1.8796) (xy 1.778 1.8796)
			)
			(stroke
				(width 0)
				(type default)
			)
			(fill no)
			(layer "F.CrtYd")
		)
		(fp_poly
			(pts
				(xy -1.778 1.8796) (xy -1.778 -1.8796) (xy 1.778 -1.8796) (xy 1.778 1.8796)
			)
			(stroke
				(width 0)
				(type default)
			)
			(fill no)
			(layer "F.Fab")
		)
		(pad "D" smd custom
			(at 0 -0.9525 180)
			(size 0.1905 0.1905)
			(layers "F.Cu" "F.Mask" "F.Paste")
			(net "SSD_ACT_DR4_MOS_N")
			(options
				(clearance outline)
				(anchor circle)
			)
			(primitives
				(gr_poly
					(pts
						(arc
							(start -0.1778 0.5715)
							(mid -0.321484 0.511984)
							(end -0.381 0.3683)
						)
						(arc
							(start -0.381 -0.3683)
							(mid -0.321484 -0.511984)
							(end -0.1778 -0.5715)
						)
						(arc
							(start 0.1778 -0.5715)
							(mid 0.321484 -0.511984)
							(end 0.381 -0.3683)
						)
						(arc
							(start 0.381 0.3683)
							(mid 0.321484 0.511984)
							(end 0.1778 0.5715)
						)
					)
					(width 0)
					(fill yes)
				)
			)
		)
		(pad "G" smd custom
			(at -0.98425 0.9525 180)
			(size 0.1905 0.1905)
			(layers "F.Cu" "F.Mask" "F.Paste")
			(net "ATTN_LED_DR4_AND_R")
			(options
				(clearance outline)
				(anchor circle)
			)
			(primitives
				(gr_poly
					(pts
						(arc
							(start -0.1778 0.5715)
							(mid -0.321484 0.511984)
							(end -0.381 0.3683)
						)
						(arc
							(start -0.381 -0.3683)
							(mid -0.321484 -0.511984)
							(end -0.1778 -0.5715)
						)
						(arc
							(start 0.1778 -0.5715)
							(mid 0.321484 -0.511984)
							(end 0.381 -0.3683)
						)
						(arc
							(start 0.381 0.3683)
							(mid 0.321484 0.511984)
							(end 0.1778 0.5715)
						)
					)
					(width 0)
					(fill yes)
				)
			)
		)
		(pad "S" smd custom
			(at 0.98425 0.9525 180)
			(size 0.1905 0.1905)
			(layers "F.Cu" "F.Mask" "F.Paste")
			(net "SSD_ACT_DR4_R")
			(options
				(clearance outline)
				(anchor circle)
			)
			(primitives
				(gr_poly
					(pts
						(arc
							(start -0.1778 0.5715)
							(mid -0.321484 0.511984)
							(end -0.381 0.3683)
						)
						(arc
							(start -0.381 -0.3683)
							(mid -0.321484 -0.511984)
							(end -0.1778 -0.5715)
						)
						(arc
							(start 0.1778 -0.5715)
							(mid 0.321484 -0.511984)
							(end 0.381 -0.3683)
						)
						(arc
							(start 0.381 0.3683)
							(mid 0.321484 0.511984)
							(end 0.1778 0.5715)
						)
					)
					(width 0)
					(fill yes)
				)
			)
		)
	)
	(footprint ""
		(layer "F.Cu")
		(at 77.089 -354.076)
		(property "Reference" "SR1050"
			(at 0 0 0)
			(layer "F.SilkS")
			(hide yes)
			(effects
				(font
					(size 1.27 1.27)
				)
			)
		)
		(property "Value" "4K7R2F-GP"
			(at 0.064008 -3.993896 0)
			(unlocked yes)
			(layer "F.Fab")
			(hide yes)
			(effects
				(font
					(size 1.016 1.016)
					(thickness 0.1524)
				)
			)
		)
		(property "Device Type" "R402H16"
			(at 0.064008 -5.517896 0)
			(unlocked yes)
			(layer "F.Fab")
			(hide yes)
			(effects
				(font
					(size 1.016 1.016)
					(thickness 0.1524)
				)
			)
		)
		(duplicate_pad_numbers_are_jumpers no)
		(fp_line
			(start -0.508 -0.9398)
			(end -0.508 0.9398)
			(stroke
				(width 0.1524)
				(type default)
			)
			(layer "F.SilkS")
		)
		(fp_line
			(start 0.508 -0.9398)
			(end -0.508 -0.9398)
			(stroke
				(width 0.1524)
				(type default)
			)
			(layer "F.SilkS")
		)
		(fp_rect
			(start -0.508 0.9398)
			(end 0.508 -0.9398)
			(stroke
				(width 0)
				(type default)
			)
			(fill no)
			(layer "F.CrtYd")
		)
		(fp_rect
			(start -0.508 0.9398)
			(end 0.508 -0.9398)
			(stroke
				(width 0)
				(type default)
			)
			(fill no)
			(layer "F.Fab")
		)
		(pad "1" smd custom
			(at 0 -0.4445)
			(size 0.1397 0.1397)
			(layers "F.Cu" "F.Mask" "F.Paste")
			(net "I2C_SW_EU17_ADDRESS_A0")
			(options
				(clearance outline)
				(anchor circle)
			)
			(primitives
				(gr_poly
					(pts
						(arc
							(start -0.1778 -0.2794)
							(mid -0.249642 -0.249642)
							(end -0.2794 -0.1778)
						)
						(arc
							(start -0.2794 0.1778)
							(mid -0.249642 0.249642)
							(end -0.1778 0.2794)
						)
						(arc
							(start 0.1778 0.2794)
							(mid 0.249642 0.249642)
							(end 0.2794 0.1778)
						)
						(arc
							(start 0.2794 -0.1778)
							(mid 0.249642 -0.249642)
							(end 0.1778 -0.2794)
						)
					)
					(width 0)
					(fill yes)
				)
			)
		)
		(pad "2" smd custom
			(at 0 0.4445)
			(size 0.1397 0.1397)
			(layers "F.Cu" "F.Mask" "F.Paste")
			(net "GND")
			(options
				(clearance outline)
				(anchor circle)
			)
			(primitives
				(gr_poly
					(pts
						(arc
							(start -0.1778 -0.2794)
							(mid -0.249642 -0.249642)
							(end -0.2794 -0.1778)
						)
						(arc
							(start -0.2794 0.1778)
							(mid -0.249642 0.249642)
							(end -0.1778 0.2794)
						)
						(arc
							(start 0.1778 0.2794)
							(mid 0.249642 0.249642)
							(end 0.2794 0.1778)
						)
						(arc
							(start 0.2794 -0.1778)
							(mid 0.249642 -0.249642)
							(end 0.1778 -0.2794)
						)
					)
					(width 0)
					(fill yes)
				)
			)
		)
	)
	(footprint ""
		(layer "F.Cu")
		(at 32.3088 -314.0964 90)
		(property "Reference" "U20"
			(at 0 0 90)
			(layer "F.SilkS")
			(hide yes)
			(effects
				(font
					(size 1.27 1.27)
				)
			)
		)
		(property "Value" "P2003EVG-GP"
			(at 0 -11.1252 90)
			(unlocked yes)
			(layer "F.Fab")
			(hide yes)
			(effects
				(font
					(size 1.016 1.016)
					(thickness 0.1524)
				)
			)
		)
		(property "Device Type" "SOIC8H79"
			(at 0 -12.6492 90)
			(unlocked yes)
			(layer "F.Fab")
			(hide yes)
			(effects
				(font
					(size 1.016 1.016)
					(thickness 0.1524)
				)
			)
		)
		(duplicate_pad_numbers_are_jumpers no)
		(fp_line
			(start 2.1336 -1.4224)
			(end -2.7432 -1.4224)
			(stroke
				(width 0.1524)
				(type default)
			)
			(layer "F.SilkS")
		)
		(fp_line
			(start -2.7432 -1.4224)
			(end -2.7432 1.4224)
			(stroke
				(width 0.1524)
				(type default)
			)
			(layer "F.SilkS")
		)
		(fp_line
			(start -2.7432 -0.508)
			(end -2.2352 0)
			(stroke
				(width 0.1524)
				(type default)
			)
			(layer "F.SilkS")
		)
		(fp_line
			(start -2.2352 0)
			(end -2.7432 0.508)
			(stroke
				(width 0.1524)
				(type default)
			)
			(layer "F.SilkS")
		)
		(fp_line
			(start 2.1336 1.4224)
			(end 2.1336 -1.4224)
			(stroke
				(width 0.1524)
				(type default)
			)
			(layer "F.SilkS")
		)
		(fp_line
			(start -2.7432 1.4224)
			(end 2.1336 1.4224)
			(stroke
				(width 0.1524)
				(type default)
			)
			(layer "F.SilkS")
		)
		(fp_line
			(start -2.6162 3.429)
			(end -2.6162 1.4732)
			(stroke
				(width 0.4064)
				(type default)
			)
			(layer "F.SilkS")
		)
		(fp_poly
			(pts
				(xy 2.2098 -1.4224) (xy 2.2098 1.4224) (xy -2.2225 1.4224) (xy -2.2225 -1.4224)
			)
			(stroke
				(width 0)
				(type default)
			)
			(fill yes)
			(layer "F.SilkS")
		)
		(fp_rect
			(start -2.4511 2.9972)
			(end 2.4511 -2.9972)
			(stroke
				(width 0)
				(type default)
			)
			(fill no)
			(layer "F.CrtYd")
		)
		(fp_poly
			(pts
				(xy -2.8194 3.6322) (xy -2.8194 -3.6322) (xy 2.8194 -3.6322) (xy 2.8194 -2.2987) (xy 2.4511 -2.2987)
				(xy 2.4511 -2.9972) (xy -2.4511 -2.9972) (xy -2.4511 2.9972) (xy 2.4511 2.9972) (xy 2.4511 -2.286)
				(xy 2.8194 -2.286) (xy 2.8194 3.6322)
			)
			(stroke
				(width 0)
				(type default)
			)
			(fill no)
			(layer "F.CrtYd")
		)
		(fp_rect
			(start -2.8194 3.6322)
			(end 2.8194 -3.6322)
			(stroke
				(width 0)
				(type default)
			)
			(fill no)
			(layer "F.Fab")
		)
		(pad "1" smd rect
			(at -1.905 2.54 90)
			(size 0.635 1.651)
			(layers "F.Cu" "F.Mask" "F.Paste")
			(net "P12V")
		)
		(pad "2" smd rect
			(at -0.635 2.54 90)
			(size 0.635 1.651)
			(layers "F.Cu" "F.Mask" "F.Paste")
			(net "P12V")
		)
		(pad "3" smd rect
			(at 0.635 2.54 90)
			(size 0.635 1.651)
			(layers "F.Cu" "F.Mask" "F.Paste")
			(net "P12V")
		)
		(pad "4" smd rect
			(at 1.905 2.54 90)
			(size 0.635 1.651)
			(layers "F.Cu" "F.Mask" "F.Paste")
			(net "SW_SSD11_N")
		)
		(pad "5" smd rect
			(at 1.905 -2.54 90)
			(size 0.635 1.651)
			(layers "F.Cu" "F.Mask" "F.Paste")
			(net "P12V_SSD11")
		)
		(pad "6" smd rect
			(at 0.635 -2.54 90)
			(size 0.635 1.651)
			(layers "F.Cu" "F.Mask" "F.Paste")
			(net "P12V_SSD11")
		)
		(pad "7" smd rect
			(at -0.635 -2.54 90)
			(size 0.635 1.651)
			(layers "F.Cu" "F.Mask" "F.Paste")
			(net "P12V_SSD11")
		)
		(pad "8" smd rect
			(at -1.905 -2.54 90)
			(size 0.635 1.651)
			(layers "F.Cu" "F.Mask" "F.Paste")
			(net "P12V_SSD11")
		)
	)
	(footprint ""
		(layer "F.Cu")
		(at 88.011 -215.519)
		(property "Reference" "C8915"
			(at 0 0 0)
			(layer "F.SilkS")
			(hide yes)
			(effects
				(font
					(size 1.27 1.27)
				)
			)
		)
		(property "Value" "SCD1U16V2KX-3GP"
			(at 1.1811 -2.7051 0)
			(unlocked yes)
			(layer "F.Fab")
			(hide yes)
			(effects
				(font
					(size 1.016 1.016)
					(thickness 0.1524)
				)
			)
		)
		(property "Device Type" "C402H22"
			(at 1.1811 -4.2291 0)
			(unlocked yes)
			(layer "F.Fab")
			(hide yes)
			(effects
				(font
					(size 1.016 1.016)
					(thickness 0.1524)
				)
			)
		)
		(duplicate_pad_numbers_are_jumpers no)
		(fp_rect
			(start -0.4318 0.9525)
			(end 0.4318 -0.9525)
			(stroke
				(width 0)
				(type default)
			)
			(fill no)
			(layer "F.CrtYd")
		)
		(fp_rect
			(start -0.4318 0.9525)
			(end 0.4318 -0.9525)
			(stroke
				(width 0)
				(type default)
			)
			(fill no)
			(layer "F.Fab")
		)
		(pad "1" smd custom
			(at 0 -0.4445)
			(size 0.1524 0.1524)
			(layers "F.Cu" "F.Mask" "F.Paste")
			(net "VDDA_3")
			(options
				(clearance outline)
				(anchor circle)
			)
			(primitives
				(gr_poly
					(pts
						(arc
							(start 0.3048 -0.2032)
							(mid 0.275042 -0.275042)
							(end 0.2032 -0.3048)
						)
						(arc
							(start -0.2032 -0.3048)
							(mid -0.275042 -0.275042)
							(end -0.3048 -0.2032)
						)
						(arc
							(start -0.3048 0.2032)
							(mid -0.275042 0.275042)
							(end -0.2032 0.3048)
						)
						(arc
							(start 0.2032 0.3048)
							(mid 0.275042 0.275042)
							(end 0.3048 0.2032)
						)
					)
					(width 0)
					(fill yes)
				)
			)
		)
		(pad "2" smd custom
			(at 0 0.4445)
			(size 0.1524 0.1524)
			(layers "F.Cu" "F.Mask" "F.Paste")
			(net "GND")
			(options
				(clearance outline)
				(anchor circle)
			)
			(primitives
				(gr_poly
					(pts
						(arc
							(start 0.3048 -0.2032)
							(mid 0.275042 -0.275042)
							(end 0.2032 -0.3048)
						)
						(arc
							(start -0.2032 -0.3048)
							(mid -0.275042 -0.275042)
							(end -0.3048 -0.2032)
						)
						(arc
							(start -0.3048 0.2032)
							(mid -0.275042 0.275042)
							(end -0.2032 0.3048)
						)
						(arc
							(start 0.2032 0.3048)
							(mid 0.275042 0.275042)
							(end 0.3048 0.2032)
						)
					)
					(width 0)
					(fill yes)
				)
			)
		)
	)
	(footprint ""
		(layer "F.Cu")
		(at 230.886 -37.199062 -90)
		(property "Reference" "R9809"
			(at 0 0 270)
			(layer "F.SilkS")
			(hide yes)
			(effects
				(font
					(size 1.27 1.27)
				)
			)
		)
		(property "Value" "0R2J-2-GP"
			(at 0.064008 -3.993896 270)
			(unlocked yes)
			(layer "F.Fab")
			(hide yes)
			(effects
				(font
					(size 1.016 1.016)
					(thickness 0.1524)
				)
			)
		)
		(property "Device Type" "R402H16"
			(at 0.064008 -5.517896 270)
			(unlocked yes)
			(layer "F.Fab")
			(hide yes)
			(effects
				(font
					(size 1.016 1.016)
					(thickness 0.1524)
				)
			)
		)
		(duplicate_pad_numbers_are_jumpers no)
		(fp_line
			(start -0.508 -0.9398)
			(end -0.508 0.9398)
			(stroke
				(width 0.1524)
				(type default)
			)
			(layer "F.SilkS")
		)
		(fp_line
			(start 0.508 -0.9398)
			(end -0.508 -0.9398)
			(stroke
				(width 0.1524)
				(type default)
			)
			(layer "F.SilkS")
		)
		(fp_rect
			(start -0.508 0.9398)
			(end 0.508 -0.9398)
			(stroke
				(width 0)
				(type default)
			)
			(fill no)
			(layer "F.CrtYd")
		)
		(fp_rect
			(start -0.508 0.9398)
			(end 0.508 -0.9398)
			(stroke
				(width 0)
				(type default)
			)
			(fill no)
			(layer "F.Fab")
		)
		(pad "1" smd custom
			(at 0 -0.4445 270)
			(size 0.1397 0.1397)
			(layers "F.Cu" "F.Mask" "F.Paste")
			(net "SSD_ACT_DR4_R")
			(options
				(clearance outline)
				(anchor circle)
			)
			(primitives
				(gr_poly
					(pts
						(arc
							(start -0.1778 -0.2794)
							(mid -0.249642 -0.249642)
							(end -0.2794 -0.1778)
						)
						(arc
							(start -0.2794 0.1778)
							(mid -0.249642 0.249642)
							(end -0.1778 0.2794)
						)
						(arc
							(start 0.1778 0.2794)
							(mid 0.249642 0.249642)
							(end 0.2794 0.1778)
						)
						(arc
							(start 0.2794 -0.1778)
							(mid 0.249642 -0.249642)
							(end 0.1778 -0.2794)
						)
					)
					(width 0)
					(fill yes)
				)
			)
		)
		(pad "2" smd custom
			(at 0 0.4445 270)
			(size 0.1397 0.1397)
			(layers "F.Cu" "F.Mask" "F.Paste")
			(net "SSD_ACT_DR4")
			(options
				(clearance outline)
				(anchor circle)
			)
			(primitives
				(gr_poly
					(pts
						(arc
							(start -0.1778 -0.2794)
							(mid -0.249642 -0.249642)
							(end -0.2794 -0.1778)
						)
						(arc
							(start -0.2794 0.1778)
							(mid -0.249642 0.249642)
							(end -0.1778 0.2794)
						)
						(arc
							(start 0.1778 0.2794)
							(mid 0.249642 0.249642)
							(end 0.2794 0.1778)
						)
						(arc
							(start 0.2794 -0.1778)
							(mid 0.249642 -0.249642)
							(end 0.1778 -0.2794)
						)
					)
					(width 0)
					(fill yes)
				)
			)
		)
	)
)
